# T6G (Grand Teton) — schematic netlist excerpt (pin names and nets, part order shuffled) for the footprints in the layout excerpt that follows; sources: Cadence DE-HDL packaged netlist, KiCad conversion of 04192023_DAF0TMB3IC0_F0TG_MB_C_brd_V02_OCP.brd

PC174_IOP0_3  Q_CAP  2.2UF 10V 10% X6S  pkg C0402  page 206 : A = PVDDCR_CPU1_P0_PVCC ; B = GND
PC320  Q_CAP  2.2UF 10V 10% X6S  pkg C0402  page 215 : A = PVDDCR_SOC_P1_VCC2 ; B = GND
H6001  HOLE  EMPTY  pkg TH  page 230 : \1\ = GND

(kicad_pcb
	(version 20260206)
	(generator "pcbnew")
	(generator_version "10.0")
	(general
		(thickness 1.6)
		(legacy_teardrops no)
	)
	(paper "A4")
	(title_block
		(title "04192023_DAF0TMB3IC0_F0TG_MB_C_brd_V02_OCP.brd")
		(comment 1 "Grand Teton / footprints 4843-4845 of 8354")
	)
	(layers
		(0 "F.Cu" signal "TOP")
		(4 "In1.Cu" signal "GND")
		(6 "In2.Cu" signal "IN1")
		(8 "In3.Cu" signal "GND1")
		(10 "In4.Cu" signal "IN2")
		(12 "In5.Cu" signal "GND2")
		(14 "In6.Cu" signal "IN3")
		(16 "In7.Cu" signal "GND3")
		(18 "In8.Cu" signal "VCC")
		(20 "In9.Cu" signal "VCC1")
		(22 "In10.Cu" signal "GND4")
		(24 "In11.Cu" signal "IN4")
		(26 "In12.Cu" signal "GND5")
		(28 "In13.Cu" signal "IN5")
		(30 "In14.Cu" signal "GND6")
		(32 "In15.Cu" signal "IN6")
		(34 "In16.Cu" signal "GND7")
		(2 "B.Cu" signal "BOTTOM")
		(9 "F.Adhes" user "F.Adhesive")
		(11 "B.Adhes" user "B.Adhesive")
		(13 "F.Paste" user "Package Geometry/Pastemask Top")
		(15 "B.Paste" user "Package Geometry/Pastemask Bottom")
		(5 "F.SilkS" user "Ref Des/Silkscreen Top")
		(7 "B.SilkS" user "Ref Des/Silkscreen Bottom")
		(1 "F.Mask" user "Board Geometry/Soldermask Top")
		(3 "B.Mask" user "Board Geometry/Soldermask Bottom")
		(17 "Dwgs.User" user "User.Drawings")
		(19 "Cmts.User" user "User.Comments")
		(21 "Eco1.User" user "User.Eco1")
		(23 "Eco2.User" user "User.Eco2")
		(25 "Edge.Cuts" user "Board Geometry/Outline")
		(27 "Margin" user)
		(31 "F.CrtYd" user "Package Geometry/Place Bound Top")
		(29 "B.CrtYd" user "Package Geometry/Place Bound Bottom")
		(35 "F.Fab" user "Ref Des/Assembly Top")
		(33 "B.Fab" user "Ref Des/Assembly Bottom")
	)
	(footprint ""
		(layer "F.Cu")
		(at 280.019506 -346.714572 -90)
		(property "Reference" "PC174_IOP0_3"
			(at 0 0 270)
			(layer "F.SilkS")
			(hide yes)
			(effects
				(font
					(size 1.27 1.27)
				)
			)
		)
		(property "Value" ""
			(at 0 0 270)
			(layer "F.Fab")
			(effects
				(font
					(size 1.27 1.27)
				)
			)
		)
		(duplicate_pad_numbers_are_jumpers no)
		(fp_line
			(start -0.7874 0.4064)
			(end -0.7874 -0.4064)
			(stroke
				(width 0.1524)
				(type default)
			)
			(layer "F.SilkS")
		)
		(fp_line
			(start 0.7874 0.4064)
			(end -0.7874 0.4064)
			(stroke
				(width 0.1524)
				(type default)
			)
			(layer "F.SilkS")
		)
		(fp_line
			(start -0.7874 -0.4064)
			(end 0.7874 -0.4064)
			(stroke
				(width 0.1524)
				(type default)
			)
			(layer "F.SilkS")
		)
		(fp_line
			(start 0.7874 -0.4064)
			(end 0.7874 0.4064)
			(stroke
				(width 0.1524)
				(type default)
			)
			(layer "F.SilkS")
		)
		(fp_line
			(start -0.67945 0.3048)
			(end -0.67945 -0.305054)
			(stroke
				(width 0.1)
				(type default)
			)
			(layer "F.Fab")
		)
		(fp_line
			(start -0.12065 0.3048)
			(end -0.67945 0.3048)
			(stroke
				(width 0.1)
				(type default)
			)
			(layer "F.Fab")
		)
		(fp_line
			(start 0.120396 0.3048)
			(end 0.120396 0.2794)
			(stroke
				(width 0.1)
				(type default)
			)
			(layer "F.Fab")
		)
		(fp_line
			(start 0.67945 0.3048)
			(end 0.120396 0.3048)
			(stroke
				(width 0.1)
				(type default)
			)
			(layer "F.Fab")
		)
		(fp_line
			(start -0.12065 0.2794)
			(end -0.12065 0.3048)
			(stroke
				(width 0.1)
				(type default)
			)
			(layer "F.Fab")
		)
		(fp_line
			(start 0.120396 0.2794)
			(end -0.12065 0.2794)
			(stroke
				(width 0.1)
				(type default)
			)
			(layer "F.Fab")
		)
		(fp_line
			(start -0.12065 -0.2794)
			(end 0.12065 -0.2794)
			(stroke
				(width 0.1)
				(type default)
			)
			(layer "F.Fab")
		)
		(fp_line
			(start 0.12065 -0.2794)
			(end 0.12065 -0.3048)
			(stroke
				(width 0.1)
				(type default)
			)
			(layer "F.Fab")
		)
		(fp_line
			(start 0.12065 -0.3048)
			(end 0.67945 -0.3048)
			(stroke
				(width 0.1)
				(type default)
			)
			(layer "F.Fab")
		)
		(fp_line
			(start 0.67945 -0.3048)
			(end 0.67945 0.3048)
			(stroke
				(width 0.1)
				(type default)
			)
			(layer "F.Fab")
		)
		(fp_line
			(start -0.67945 -0.305054)
			(end -0.12065 -0.305054)
			(stroke
				(width 0.1)
				(type default)
			)
			(layer "F.Fab")
		)
		(fp_line
			(start -0.12065 -0.305054)
			(end -0.12065 -0.2794)
			(stroke
				(width 0.1)
				(type default)
			)
			(layer "F.Fab")
		)
		(pad "1" smd circle
			(at -0.40005 0 270)
			(size 0 0)
			(layers "F.Cu" "F.Mask" "F.Paste")
			(net "PVDDCR_CPU1_P0_PVCC")
		)
		(pad "2" smd circle
			(at 0.40005 0 270)
			(size 0 0)
			(layers "F.Cu" "F.Mask" "F.Paste")
			(net "GND")
		)
	)
	(footprint ""
		(layer "F.Cu")
		(at 466.8901 -51.289966)
		(property "Reference" "H6001"
			(at -2.5146 -4.17957 0)
			(unlocked yes)
			(layer "F.SilkS")
			(effects
				(font
					(size 0.7874 0.5842)
					(thickness 0.1524)
				)
				(justify left)
			)
		)
		(property "Value" ""
			(at 0 0 0)
			(layer "F.Fab")
			(effects
				(font
					(size 1.27 1.27)
				)
			)
		)
		(duplicate_pad_numbers_are_jumpers no)
		(pad "1" thru_hole circle
			(at 0 0)
			(size 6.1976 6.1976)
			(drill 3.7338)
			(layers "*.Cu" "*.Mask")
			(remove_unused_layers no)
			(net "GND")
			(clearance -0.9779)
			(padstack
				(mode front_inner_back)
				(layer "Inner"
					(shape circle)
					(size 5.5372 5.5372)
					(clearance -0.6477)
				)
				(layer "B.Cu"
					(shape circle)
					(size 6.1976 6.1976)
					(clearance -0.9779)
				)
			)
		)
	)
	(footprint ""
		(layer "F.Cu")
		(at 127.64897 -162.527234 -90)
		(property "Reference" "PC320"
			(at 0 0 270)
			(layer "F.SilkS")
			(hide yes)
			(effects
				(font
					(size 1.27 1.27)
				)
			)
		)
		(property "Value" ""
			(at 0 0 270)
			(layer "F.Fab")
			(effects
				(font
					(size 1.27 1.27)
				)
			)
		)
		(duplicate_pad_numbers_are_jumpers no)
		(fp_line
			(start -0.7874 0.4064)
			(end -0.7874 -0.4064)
			(stroke
				(width 0.1524)
				(type default)
			)
			(layer "F.SilkS")
		)
		(fp_line
			(start -0.286766 0.4064)
			(end -0.7874 0.4064)
			(stroke
				(width 0.1524)
				(type default)
			)
			(layer "F.SilkS")
		)
		(fp_line
			(start 0.7874 0.4064)
			(end 0.348234 0.4064)
			(stroke
				(width 0.1524)
				(type default)
			)
			(layer "F.SilkS")
		)
		(fp_line
			(start -0.7874 -0.4064)
			(end 0.7874 -0.4064)
			(stroke
				(width 0.1524)
				(type default)
			)
			(layer "F.SilkS")
		)
		(fp_line
			(start 0.7874 -0.4064)
			(end 0.7874 0.4064)
			(stroke
				(width 0.1524)
				(type default)
			)
			(layer "F.SilkS")
		)
		(fp_line
			(start -0.67945 0.3048)
			(end -0.67945 -0.305054)
			(stroke
				(width 0.1)
				(type default)
			)
			(layer "F.Fab")
		)
		(fp_line
			(start -0.12065 0.3048)
			(end -0.67945 0.3048)
			(stroke
				(width 0.1)
				(type default)
			)
			(layer "F.Fab")
		)
		(fp_line
			(start 0.120396 0.3048)
			(end 0.120396 0.2794)
			(stroke
				(width 0.1)
				(type default)
			)
			(layer "F.Fab")
		)
		(fp_line
			(start 0.67945 0.3048)
			(end 0.120396 0.3048)
			(stroke
				(width 0.1)
				(type default)
			)
			(layer "F.Fab")
		)
		(fp_line
			(start -0.12065 0.2794)
			(end -0.12065 0.3048)
			(stroke
				(width 0.1)
				(type default)
			)
			(layer "F.Fab")
		)
		(fp_line
			(start 0.120396 0.2794)
			(end -0.12065 0.2794)
			(stroke
				(width 0.1)
				(type default)
			)
			(layer "F.Fab")
		)
		(fp_line
			(start -0.12065 -0.2794)
			(end 0.12065 -0.2794)
			(stroke
				(width 0.1)
				(type default)
			)
			(layer "F.Fab")
		)
		(fp_line
			(start 0.12065 -0.2794)
			(end 0.12065 -0.3048)
			(stroke
				(width 0.1)
				(type default)
			)
			(layer "F.Fab")
		)
		(fp_line
			(start 0.12065 -0.3048)
			(end 0.67945 -0.3048)
			(stroke
				(width 0.1)
				(type default)
			)
			(layer "F.Fab")
		)
		(fp_line
			(start 0.67945 -0.3048)
			(end 0.67945 0.3048)
			(stroke
				(width 0.1)
				(type default)
			)
			(layer "F.Fab")
		)
		(fp_line
			(start -0.67945 -0.305054)
			(end -0.12065 -0.305054)
			(stroke
				(width 0.1)
				(type default)
			)
			(layer "F.Fab")
		)
		(fp_line
			(start -0.12065 -0.305054)
			(end -0.12065 -0.2794)
			(stroke
				(width 0.1)
				(type default)
			)
			(layer "F.Fab")
		)
		(pad "1" smd circle
			(at -0.40005 0 270)
			(size 0 0)
			(layers "F.Cu" "F.Mask" "F.Paste")
			(net "PVDDCR_SOC_P1_VCC2")
		)
		(pad "2" smd circle
			(at 0.40005 0 270)
			(size 0 0)
			(layers "F.Cu" "F.Mask" "F.Paste")
			(net "GND")
		)
	)
)
